#ISCELL
  pure_quanta quanta_title_block_c *
  *
#ISCELL
  logical_power universal_gnd *
  page71_i1
#CELL
  pure_quanta socket4677_azif0045p001c01cs *
  page71_i2
#ISCELL
  logical_power universal_gnd *
  page71_i3
#ISCELL
  logical_power universal_gnd *
  page71_i4
#CELL
  pure_quanta socket4677_azif0045p001c01cs *
  page71_i5
#ISCELL
  logical_power universal_gnd *
  page71_i6
#ISCELL
  logical_power universal_gnd *
  page71_i7
#CELL
  pure_quanta socket4677_azif0045p001c01cs *
  page71_i8
#ISCELL
  logical_power universal_gnd *
  page71_i9
